#ISCELL
  mstr_misc dns *
  *
#ISCELL
  pure_quanta quanta_title_block_c *
  *
#ISCELL
  logical_power universal_gnd *
  page256_i1
#ISCELL
  logical_power universal_gnd *
  page256_i10
#CELL
  pure_quanta q_cap *
  page256_i11
#CELL
  pure_quanta q_res *
  page256_i12
#ISCELL
  logical_power vcc15 *
  page256_i13
#ISCELL
  logical_power universal_gnd *
  page256_i14
#CELL
  pure_quanta q_cap *
  page256_i15
#ISCELL
  logical_power universal_gnd *
  page256_i16
#CELL
  pure_quanta q_cap *
  page256_i17
#ISCELL
  standard offpage *
  page256_i18
#CELL
  pure_quanta q_res *
  page256_i19
#CELL
  pure_quanta isl99390frztr5935 *
  page256_i2
#CELL
  pure_quanta q_cap *
  page256_i20
#CELL
  pure_quanta q_cap *
  page256_i21
#ISCELL
  logical_power universal_gnd *
  page256_i22
#CELL
  pure_quanta q_res *
  page256_i23
#ISCELL
  standard offpage *
  page256_i24
#ISCELL
  standard offpage *
  page256_i25
#ISCELL
  logical_power universal_gnd *
  page256_i26
#ISCELL
  standard offpage *
  page256_i27
#ISCELL
  standard offpage *
  page256_i28
#CELL
  pure_quanta q_cap *
  page256_i29
#ISCELL
  logical_power universal_gnd *
  page256_i3
#ISCELL
  logical_power universal_gnd *
  page256_i30
#CELL
  pure_quanta q_cap *
  page256_i31
#CELL
  pure_quanta isl99390frztr5935 *
  page256_i32
#CELL
  pure_quanta q_res *
  page256_i33
#ISCELL
  logical_power vcc15 *
  page256_i34
#ISCELL
  logical_power universal_gnd *
  page256_i35
#CELL
  pure_quanta q_cap *
  page256_i36
#ISCELL
  logical_power universal_gnd *
  page256_i37
#ISCELL
  logical_power universal_gnd *
  page256_i38
#CELL
  pure_quanta q_inductor *
  page256_i39
#CELL
  pure_quanta q_res *
  page256_i4
#CELL
  pure_quanta q_res *
  page256_i40
#CELL
  pure_quanta q_cap *
  page256_i41
#CELL
  pure_quanta q_cap *
  page256_i42
#CELL
  pure_quanta q_cap *
  page256_i43
#CELL
  pure_quanta q_inductor4p_14 *
  page256_i44
#CELL
  pure_quanta q_cap *
  page256_i45
#CELL
  pure_quanta q_res *
  page256_i46
#CELL
  pure_quanta q_cap *
  page256_i47
#CELL
  pure_quanta q_cap *
  page256_i48
#ISCELL
  logical_power universal_gnd *
  page256_i49
#ISCELL
  standard offpage *
  page256_i5
#ISCELL
  logical_power vcc15 *
  page256_i50
#ISCELL
  logical_power universal_gnd *
  page256_i51
#CELL
  pure_quanta q_cap *
  page256_i52
#CELL
  pure_quanta q_cap *
  page256_i53
#CELL
  pure_quanta q_cap *
  page256_i54
#ISCELL
  logical_power universal_gnd *
  page256_i55
#ISCELL
  logical_power vcc15 *
  page256_i56
#CELL
  pure_quanta q_res *
  page256_i57
#CELL
  pure_quanta q_inductor4p_14 *
  page256_i58
#CELL
  pure_quanta q_cap *
  page256_i59
#ISCELL
  standard offpage *
  page256_i6
#ISCELL
  logical_power universal_gnd *
  page256_i60
#ISCELL
  standard offpage *
  page256_i61
#CELL
  pure_quanta q_cap *
  page256_i62
#CELL
  pure_quanta q_cap *
  page256_i63
#CELL
  pure_quanta q_cap *
  page256_i64
#ISCELL
  logical_power vcc15 *
  page256_i65
#CELL
  pure_quanta q_cap *
  page256_i66
#CELL
  pure_quanta q_cap *
  page256_i67
#ISCELL
  logical_power universal_gnd *
  page256_i68
#ISCELL
  logical_power vcc15 *
  page256_i69
#CELL
  pure_quanta q_cap *
  page256_i7
#ISCELL
  standard offpage *
  page256_i8
#ISCELL
  standard offpage *
  page256_i9
